# T6G (Grand Teton) — schematic netlist excerpt (pin names and nets, part order shuffled) for the footprints in the layout excerpt that follows; sources: Cadence DE-HDL packaged netlist, KiCad conversion of 04192023_DAF0TMB3IC0_F0TG_MB_C_brd_V02_OCP.brd

C366  Q_CAP  100UF 4V 20% X6S  pkg C0805  page 345 : A = P1V8_CPU1_RT_1D ; B = GND
R3934  Q_RES  22 1% CHIP  pkg 0402LF  page 262 : A = HSC_D_OC_R ; B = HSC_D_OC
C1821  Q_CAP  0.1UF 25V 10% X7R  pkg 0402  page 139 : A = P3V3_AUX ; B = GND

(kicad_pcb
	(version 20260206)
	(generator "pcbnew")
	(generator_version "10.0")
	(general
		(thickness 1.6)
		(legacy_teardrops no)
	)
	(paper "A4")
	(title_block
		(title "04192023_DAF0TMB3IC0_F0TG_MB_C_brd_V02_OCP.brd")
		(comment 1 "Grand Teton / footprints 3887-3889 of 8354")
	)
	(layers
		(0 "F.Cu" signal "TOP")
		(4 "In1.Cu" signal "GND")
		(6 "In2.Cu" signal "IN1")
		(8 "In3.Cu" signal "GND1")
		(10 "In4.Cu" signal "IN2")
		(12 "In5.Cu" signal "GND2")
		(14 "In6.Cu" signal "IN3")
		(16 "In7.Cu" signal "GND3")
		(18 "In8.Cu" signal "VCC")
		(20 "In9.Cu" signal "VCC1")
		(22 "In10.Cu" signal "GND4")
		(24 "In11.Cu" signal "IN4")
		(26 "In12.Cu" signal "GND5")
		(28 "In13.Cu" signal "IN5")
		(30 "In14.Cu" signal "GND6")
		(32 "In15.Cu" signal "IN6")
		(34 "In16.Cu" signal "GND7")
		(2 "B.Cu" signal "BOTTOM")
		(9 "F.Adhes" user "F.Adhesive")
		(11 "B.Adhes" user "B.Adhesive")
		(13 "F.Paste" user "Package Geometry/Pastemask Top")
		(15 "B.Paste" user "Package Geometry/Pastemask Bottom")
		(5 "F.SilkS" user "Ref Des/Silkscreen Top")
		(7 "B.SilkS" user "Ref Des/Silkscreen Bottom")
		(1 "F.Mask" user "Board Geometry/Soldermask Top")
		(3 "B.Mask" user "Board Geometry/Soldermask Bottom")
		(17 "Dwgs.User" user "User.Drawings")
		(19 "Cmts.User" user "User.Comments")
		(21 "Eco1.User" user "User.Eco1")
		(23 "Eco2.User" user "User.Eco2")
		(25 "Edge.Cuts" user "Board Geometry/Outline")
		(27 "Margin" user)
		(31 "F.CrtYd" user "Package Geometry/Place Bound Top")
		(29 "B.CrtYd" user "Package Geometry/Place Bound Bottom")
		(35 "F.Fab" user "Ref Des/Assembly Top")
		(33 "B.Fab" user "Ref Des/Assembly Bottom")
	)
	(footprint ""
		(layer "F.Cu")
		(at 85.322156 -41.95318)
		(property "Reference" "C1821"
			(at 0 0 0)
			(layer "F.SilkS")
			(hide yes)
			(effects
				(font
					(size 1.27 1.27)
				)
			)
		)
		(property "Value" ""
			(at 0 0 0)
			(layer "F.Fab")
			(effects
				(font
					(size 1.27 1.27)
				)
			)
		)
		(duplicate_pad_numbers_are_jumpers no)
		(fp_line
			(start -0.7874 -0.4064)
			(end 0.7874 -0.4064)
			(stroke
				(width 0.1524)
				(type default)
			)
			(layer "F.SilkS")
		)
		(fp_line
			(start -0.7874 0.4064)
			(end -0.7874 -0.4064)
			(stroke
				(width 0.1524)
				(type default)
			)
			(layer "F.SilkS")
		)
		(fp_line
			(start 0.7874 -0.4064)
			(end 0.7874 0.4064)
			(stroke
				(width 0.1524)
				(type default)
			)
			(layer "F.SilkS")
		)
		(fp_line
			(start 0.7874 0.4064)
			(end -0.7874 0.4064)
			(stroke
				(width 0.1524)
				(type default)
			)
			(layer "F.SilkS")
		)
		(fp_line
			(start -0.67945 -0.305054)
			(end -0.12065 -0.305054)
			(stroke
				(width 0.1)
				(type default)
			)
			(layer "F.Fab")
		)
		(fp_line
			(start -0.67945 0.3048)
			(end -0.67945 -0.305054)
			(stroke
				(width 0.1)
				(type default)
			)
			(layer "F.Fab")
		)
		(fp_line
			(start -0.12065 -0.305054)
			(end -0.12065 -0.2794)
			(stroke
				(width 0.1)
				(type default)
			)
			(layer "F.Fab")
		)
		(fp_line
			(start -0.12065 -0.2794)
			(end 0.12065 -0.2794)
			(stroke
				(width 0.1)
				(type default)
			)
			(layer "F.Fab")
		)
		(fp_line
			(start -0.12065 0.2794)
			(end -0.12065 0.3048)
			(stroke
				(width 0.1)
				(type default)
			)
			(layer "F.Fab")
		)
		(fp_line
			(start -0.12065 0.3048)
			(end -0.67945 0.3048)
			(stroke
				(width 0.1)
				(type default)
			)
			(layer "F.Fab")
		)
		(fp_line
			(start 0.120396 0.2794)
			(end -0.12065 0.2794)
			(stroke
				(width 0.1)
				(type default)
			)
			(layer "F.Fab")
		)
		(fp_line
			(start 0.120396 0.3048)
			(end 0.120396 0.2794)
			(stroke
				(width 0.1)
				(type default)
			)
			(layer "F.Fab")
		)
		(fp_line
			(start 0.12065 -0.3048)
			(end 0.67945 -0.3048)
			(stroke
				(width 0.1)
				(type default)
			)
			(layer "F.Fab")
		)
		(fp_line
			(start 0.12065 -0.2794)
			(end 0.12065 -0.3048)
			(stroke
				(width 0.1)
				(type default)
			)
			(layer "F.Fab")
		)
		(fp_line
			(start 0.67945 -0.3048)
			(end 0.67945 0.3048)
			(stroke
				(width 0.1)
				(type default)
			)
			(layer "F.Fab")
		)
		(fp_line
			(start 0.67945 0.3048)
			(end 0.120396 0.3048)
			(stroke
				(width 0.1)
				(type default)
			)
			(layer "F.Fab")
		)
		(pad "1" smd circle
			(at -0.40005 0)
			(size 0 0)
			(layers "F.Cu" "F.Mask" "F.Paste")
			(net "P3V3_AUX")
		)
		(pad "2" smd circle
			(at 0.40005 0)
			(size 0 0)
			(layers "F.Cu" "F.Mask" "F.Paste")
			(net "GND")
		)
	)
	(footprint ""
		(layer "F.Cu")
		(at 191.41694 -400.309842)
		(property "Reference" "R3934"
			(at 0 0 0)
			(layer "F.SilkS")
			(hide yes)
			(effects
				(font
					(size 1.27 1.27)
				)
			)
		)
		(property "Value" ""
			(at 0 0 0)
			(layer "F.Fab")
			(effects
				(font
					(size 1.27 1.27)
				)
			)
		)
		(duplicate_pad_numbers_are_jumpers no)
		(fp_line
			(start -0.7874 -0.4064)
			(end 0.7874 -0.4064)
			(stroke
				(width 0.1524)
				(type default)
			)
			(layer "F.SilkS")
		)
		(fp_line
			(start -0.7874 0.4064)
			(end -0.7874 -0.4064)
			(stroke
				(width 0.1524)
				(type default)
			)
			(layer "F.SilkS")
		)
		(fp_line
			(start 0.7874 -0.4064)
			(end 0.7874 0.4064)
			(stroke
				(width 0.1524)
				(type default)
			)
			(layer "F.SilkS")
		)
		(fp_line
			(start 0.7874 0.4064)
			(end -0.7874 0.4064)
			(stroke
				(width 0.1524)
				(type default)
			)
			(layer "F.SilkS")
		)
		(fp_line
			(start -0.67945 -0.305054)
			(end -0.12065 -0.305054)
			(stroke
				(width 0.1)
				(type default)
			)
			(layer "F.Fab")
		)
		(fp_line
			(start -0.67945 0.3048)
			(end -0.67945 -0.305054)
			(stroke
				(width 0.1)
				(type default)
			)
			(layer "F.Fab")
		)
		(fp_line
			(start -0.12065 -0.305054)
			(end -0.12065 -0.2794)
			(stroke
				(width 0.1)
				(type default)
			)
			(layer "F.Fab")
		)
		(fp_line
			(start -0.12065 -0.2794)
			(end 0.12065 -0.2794)
			(stroke
				(width 0.1)
				(type default)
			)
			(layer "F.Fab")
		)
		(fp_line
			(start -0.12065 0.2794)
			(end -0.12065 0.3048)
			(stroke
				(width 0.1)
				(type default)
			)
			(layer "F.Fab")
		)
		(fp_line
			(start -0.12065 0.3048)
			(end -0.67945 0.3048)
			(stroke
				(width 0.1)
				(type default)
			)
			(layer "F.Fab")
		)
		(fp_line
			(start 0.120396 0.2794)
			(end -0.12065 0.2794)
			(stroke
				(width 0.1)
				(type default)
			)
			(layer "F.Fab")
		)
		(fp_line
			(start 0.120396 0.3048)
			(end 0.120396 0.2794)
			(stroke
				(width 0.1)
				(type default)
			)
			(layer "F.Fab")
		)
		(fp_line
			(start 0.12065 -0.3048)
			(end 0.67945 -0.3048)
			(stroke
				(width 0.1)
				(type default)
			)
			(layer "F.Fab")
		)
		(fp_line
			(start 0.12065 -0.2794)
			(end 0.12065 -0.3048)
			(stroke
				(width 0.1)
				(type default)
			)
			(layer "F.Fab")
		)
		(fp_line
			(start 0.67945 -0.3048)
			(end 0.67945 0.3048)
			(stroke
				(width 0.1)
				(type default)
			)
			(layer "F.Fab")
		)
		(fp_line
			(start 0.67945 0.3048)
			(end 0.120396 0.3048)
			(stroke
				(width 0.1)
				(type default)
			)
			(layer "F.Fab")
		)
		(pad "1" smd circle
			(at -0.40005 0)
			(size 0 0)
			(layers "F.Cu" "F.Mask" "F.Paste")
			(net "HSC_D_OC_R")
		)
		(pad "2" smd circle
			(at 0.40005 0)
			(size 0 0)
			(layers "F.Cu" "F.Mask" "F.Paste")
			(net "HSC_D_OC")
		)
	)
	(footprint ""
		(layer "F.Cu")
		(at 173.2788 -385.5212 90)
		(property "Reference" "C366"
			(at 0 0 90)
			(layer "F.SilkS")
			(hide yes)
			(effects
				(font
					(size 1.27 1.27)
				)
			)
		)
		(property "Value" ""
			(at 0 0 90)
			(layer "F.Fab")
			(effects
				(font
					(size 1.27 1.27)
				)
			)
		)
		(duplicate_pad_numbers_are_jumpers no)
		(fp_line
			(start 1.524 -0.762)
			(end 1.524 0.762)
			(stroke
				(width 0.1524)
				(type default)
			)
			(layer "F.SilkS")
		)
		(fp_line
			(start -1.524 -0.762)
			(end 1.524 -0.762)
			(stroke
				(width 0.1524)
				(type default)
			)
			(layer "F.SilkS")
		)
		(fp_line
			(start 1.524 0.762)
			(end -1.524 0.762)
			(stroke
				(width 0.1524)
				(type default)
			)
			(layer "F.SilkS")
		)
		(fp_line
			(start -1.524 0.762)
			(end -1.524 -0.762)
			(stroke
				(width 0.1524)
				(type default)
			)
			(layer "F.SilkS")
		)
		(fp_line
			(start 1.1049 -0.724916)
			(end -1.1049 -0.724916)
			(stroke
				(width 0.1)
				(type default)
			)
			(layer "F.Fab")
		)
		(fp_line
			(start -1.1049 -0.724916)
			(end -1.1049 0.724916)
			(stroke
				(width 0.1)
				(type default)
			)
			(layer "F.Fab")
		)
		(fp_line
			(start 1.1049 0.724916)
			(end 1.1049 -0.724916)
			(stroke
				(width 0.1)
				(type default)
			)
			(layer "F.Fab")
		)
		(fp_line
			(start -1.1049 0.724916)
			(end 1.1049 0.724916)
			(stroke
				(width 0.1)
				(type default)
			)
			(layer "F.Fab")
		)
		(pad "1" smd rect
			(at -0.889 0 270)
			(size 1.016 1.27)
			(layers "F.Cu" "F.Mask" "F.Paste")
			(net "P1V8_CPU1_RT_1D")
		)
		(pad "2" smd rect
			(at 0.889 0 270)
			(size 1.016 1.27)
			(layers "F.Cu" "F.Mask" "F.Paste")
			(net "GND")
		)
	)
)
